 
 
Open CloudServer OCS 
Blade Specification 
Version 2.1 
 
 
 
 
Author: 
Mark Shaw, Director of Hardware Engineering, Microsoft 
Martin Goldstein, Principal Hardware Engineer, Microsoft 
Mark A. Shaw, Senior Hardware Engineering Manager, Microsoft 
 



Open Compute Project  Open CloudServer OCS Blade 
http://opencompute.org ii 
Revision History 
Date Description 
10/30/2014 Version 2.0 
2/3/2016 Version 2.1 – Major updates 
 Support for full width blades 
 Support for Future Intel® Xeon® Processor product family, 135W maximum 
 Decreased HDD support to enable cooling for 135W processors 
 Eliminated support for 10G networking 
 Support for external SAS attached JBOD has been removed 
 
  



Open Compute Project  Open CloudServer OCS Blade 
http://opencompute.org iii 
 
© 2016 Microsoft Corporation. 
As of October 30, 2014, the following persons or entities have made this Specification available under the Open Web 
Foundation Final Specification Agreement (OWFa 1.0), which is available at http://www.openwebfoundation.org/legal/the-owf-
1-0-agreements/owfa-1-0 
Microsoft Corporation.  
You can review the signed copies of the Open Web Foundation Agreement Version 1.0 for this Specification at 
http://opencompute.org/licensing/, which may also include additional parties to those listed above. 
Your use of this Specification may be subject to other third party rights. THIS SPECIFICATION IS PROVIDED "AS IS." The 
contributors expressly disclaim any warranties (express, implied, or otherwise), including implied warranties of merchantability, 
noninfringement, fitness for a particular purpose, or title, related to the Specification. The entire risk as to implementing or 
otherwise using the Specification is assumed by the Specification implementer and user. IN NO EVENT WILL ANY PARTY BE 
LIABLE TO ANY OTHER PARTY FOR LOST PROFITS OR ANY FORM OF INDIRECT, SPECIAL, INCIDENTAL, OR CONSEQUENTIAL 
DAMAGES OF ANY CHARACTER FROM ANY CAUSES OF ACTION OF ANY KIND WITH RESPECT TO THIS SPECIFICATION OR ITS 
GOVERNING AGREEMENT, WHETHER BASED ON BREACH OF CONTRACT, TORT (INCLUDING NEGLIGENCE), OR OTHERWISE, AND 
WHETHER OR NOT THE OTHER PARTY HAS BEEN ADVISED OF THE POSSIBILITY OF SUCH DAMAGE. 
CONTRIBUTORS AND LICENSORS OF THIS SPECIFICATION MAY HAVE MENTIONED CERTAIN TECHNOLOGIES THAT ARE MERELY 
REFERENCED WITHIN THIS SPECIFICATION AND NOT LICENSED UNDER THE OWF CLA OR OWFa. THE FOLLOWING IS A LIST OF 
MERELY REFERENCED TECHNOLOGY: INTELLIGENT PLATFORM MANAGEMENT INTERFACE (IPMI), I2C TRADEMARK OF PHILLIPS 
SEMICONDUCTOR. IMPLEMENTATION OF THESE TECHNOLOGIES MAY BE SUBJECT TO THEIR OWN LEGAL TERMS.  



 
iv January 7, 2016 
 
 
Contents 
1 Overview of V2.1 Open CloudServer Specifications ....................................................................................... 1 
2 Introduction to the Open CloudServer System .............................................................................................. 1 
3 Blade Block Diagram ...................................................................................................................................... 4 
4 Blade Features ............................................................................................................................................... 5 
5 Labelling and Loading Guidelines .................................................................................................................. 7 
5.1 Component Labelling ................................................................................................................................... 7 
5.2 DIMMS ......................................................................................................................................................... 7 
5.3 PCIe Riser Slots ............................................................................................................................................. 8 
5.4 HDDs ............................................................................................................................................................. 8 
6 PCB Stackup .................................................................................................................................................. 8 
7 High-Speed Interface Topologies ................................................................................................................. 10 
7.1 PCIe-to-Tray Backplane Mezzanine Topology ............................................................................................ 10 
7.2 Blade-to-NIC Mezzanine Topology ............................................................................................................. 11 
7.3 PCIe M.2 Topology ..................................................................................................................................... 11 
7.4 Blade PCIe Riser Topology .......................................................................................................................... 11 
8 Datasafe Storage Support ............................................................................................................................ 12 
8.1 M.2 ............................................................................................................................................................. 12 
9 Blade Interconnects ..................................................................................................................................... 12 
9.1 Tray Backplane Interface ............................................................................................................................ 13 
9.1.1 AirMax VS2 PCIe Connector ................................................................................................................... 15 
9.1.2 AirMax VS2 10/40GbE Connector .......................................................................................................... 17 
9.1.3 AirMax VS2 SAS Connector .................................................................................................................... 19 
9.1.4 Connector Skew Compensation ............................................................................................................. 19 
9.2 PCIe M.2 Interposer Modules ..................................................................................................................... 20 
9.3 NIC Mezzanine Connector .......................................................................................................................... 23 
9.4 SATA Cable Ports ........................................................................................................................................ 25 
9.5 SATA Power Connector ............................................................................................................................... 25 
9.6 SATA HDD Connector.................................................................................................................................. 26 
9.7 LED Cable Connector .................................................................................................................................. 27 
10 Management Subsystem ............................................................................................................................. 27 
10.1 Baseboard Management Controller ........................................................................................................... 28 
10.2 DRAM ......................................................................................................................................................... 28 



Open Compute Project  Open CloudServer OCS Blade 
http://opencompute.org v 
 
10.3 BMC Boot Flash .......................................................................................................................................... 29 
10.4 BIOS Flash ................................................................................................................................................... 29 
10.5 Serial Links .................................................................................................................................................. 29 
10.6 PECI ............................................................................................................................................................ 29 
10.7 TPM Module ............................................................................................................................................... 29 
10.8 PCH/BMC I2C .............................................................................................................................................. 30 
10.8.1 Voltage Regulators ............................................................................................................................ 30 
10.8.2 Clock Generators and Buffers ............................................................................................................ 31 
10.8.3 FRUID PROM ...................................................................................................................................... 31 
10.8.4 Temperature Sensors ........................................................................................................................ 31 
10.8.5 Hot Swap Controller .......................................................................................................................... 31 
10.8.6 PCIe I2C .............................................................................................................................................. 34 
10.9 Intel® Node Manager Hardware Requirements ......................................................................................... 34 
10.10 Blade LEDs .............................................................................................................................................. 35 
10.10.1 Blade Power Status LED ..................................................................................................................... 35 
10.10.2 Blade Attention LED .......................................................................................................................... 36 
10.11 Debug Features ...................................................................................................................................... 36 
10.12 Power Capping ....................................................................................................................................... 37 
10.13 Tray Mezzanine Power Control .............................................................................................................. 38 
10.14 Connector Quality .................................................................................................................................. 38 
10.15 Overcurrent Protection .......................................................................................................................... 39 
11 NIC Mezzanine ............................................................................................................................................. 39 
12 Blade Electrical Specifications ..................................................................................................................... 39 
12.1 Input Voltage, Power, and Current ............................................................................................................. 40 
12.2 Current Interrupt Protection and Power, Voltage, and Current Monitoring  .............................................. 40 
12.3 Filtering and Capacitance ........................................................................................................................... 40 
12.4 Grounding and Return ................................................................................................................................ 41 
13 Blade Physical Specifications ....................................................................................................................... 41 
13.1 Blade Mechanical Control Outline .............................................................................................................. 41 
13.2 Volumetric Specifications ........................................................................................................................... 42 
13.3 Weight and Structure ................................................................................................................................. 45 
13.4 Guiding and Latching Features................................................................................................................... 45 
13.4.1 Latching Feature Identification ......................................................................................................... 45 
13.4.2 Guiding and Latching ......................................................................................................................... 46 
13.4.3 Electromagnetic Interference Mitigation .......................................................................................... 48 
14 Blade Thermal Design .................................................................................................................................. 49 



 
vi January 7, 2016 
 
 
Table of Figures 
Figure 1: View of OCS with rack .................................................................................................................... 2 
Figure 2: Second view of OCS........................................................................................................................ 2 
Figure 3: V2.1 OCS half-width blade ............................................................................................................. 3 
Figure 4 V2.1 OCS full-width blade ............................................................................................................... 4 
Figure 5: Baseline configuration of blade ..................................................................................................... 5 
Figure 7 Major Component Labeling ............................................................................................................ 7 
Figure 8: PCB Stackup ................................................................................................................................... 9 
Figure 9: CPU-to-tray backplane mezzanine PCIe link topology ................................................................. 10 
Figure 10: NIC 40GbE Topology .................................................................................................................. 11 
Figure 11: PCIe M.2 topology ...................................................................................................................... 11 
Figure 12: Blade PCIe riser topology ........................................................................................................... 12 
Figure 13: AirMax power receptacle pinout arrangement ......................................................................... 14 
Figure 14: Example of a coplanar blade signal connector .......................................................................... 14 
Figure 15: AirMax VS2 pinout arrangement ............................................................................................... 15 
Figure 16: Blade management block diagram ............................................................................................ 28 
Figure 17: PCH / BMC I2C block diagram .................................................................................................... 30 
Figure 18: Temperature sensor locations ................................................................................................... 31 
Figure 19: HSC functional block diagram .................................................................................................... 33 
Figure 20: Front blade LED locations .......................................................................................................... 35 
Figure 21: Rear attention LED location ....................................................................................................... 35 
Figure 22. Power Capping Block Diagram ................................................................................................... 38 
Figure 23:  NIC block diagram ..................................................................................................................... 39 
Figure 24: Mechanical control outline ........................................................................................................ 42 
Figure 25: Dimensions of the volume that holds the blade ........................................................................ 43 
Figure 26: Two blades on a single tray ........................................................................................................ 43 
Figure 27: Blade-mounting envelope, rear view ......................................................................................... 44 
Figure 28: Front surface dimple .................................................................................................................. 45 
Figure 29: Guide and latch details, top view............................................................................................... 47 
Figure 30. Example of a front-blade guide and latch .................................................................................. 48 
Figure 31: Example of a rear-blade guide pin ............................................................................................. 48 
Figure 32: Tray with EMI enclosure, blade volume shown ......................................................................... 49 
Figure 33: Blade EMI seal ............................................................................................................................ 49 
Table of Tables 
Table 1: List of specifications ........................................................................................................................ 1 
Table 2: Blade features ................................................................................................................................. 6 
Table 3: Disk Drive SATA Port Assignments .................................................................................................. 8 



Open Compute Project  Open CloudServer OCS Blade 
http://opencompute.org vii 
 
Table 4: PCIe port mapping ........................................................................................................................... 9 
Table 5: Blade-to-tray backplane connector list ......................................................................................... 12 
Table 6: Power connector pinout ............................................................................................................... 14 
Table 7: AirMax VS2 PCIe connector pinout ............................................................................................... 15 
Table 8: AirMax VS2 PCIe signal definitions ................................................................................................ 16 
Table 9: PCIe bifurcation mapping .............................................................................................................. 17 
Table 10: AirMax VS2 10/40GbE connector pinout .................................................................................... 18 
Table 11: AirMax VS2 40GbE signal definitions .......................................................................................... 18 
Table 12: AirMax VS2 SAS connector pinout .............................................................................................. 19 
Table 13: AirMax VS2 SAS signal definitions ............................................................................................... 19 
Table 14: PCIe M.2 interposer connector pinout........................................................................................ 20 
Table 15: PCIe M.2 carrier signal definitions .............................................................................................. 22 
Table 16: NIC mezzanine connector part numbers .................................................................................... 23 
Table 17: NIC mezzanine connector pinout ................................................................................................ 24 
Table 18: NIC mezzanine signal descriptions .............................................................................................. 24 
Table 19: SATA power connector signal names and current capacities ..................................................... 26 
Table 20: SATA HDD connector pinout ....................................................................................................... 26 
Table 21: Signal interpretation ................................................................................................................... 34 
Table 22: Blade power status LED description ............................................................................................ 36 
Table 23: Blade attention LED description .................................................................................................. 36 
Table 24: Input voltage range ..................................................................................................................... 40 
Table 25: Input power and current allocation ............................................................................................ 40 




Open Compute Project  Open CloudServer OCS Blade 
http://opencompute.org 1 
1 Overview of V2.1 Open CloudServer Specifications 
Table 1 lists the Open CloudServer (OCS) system specifications. 
Table 1: List of specifications 
Specification title Description 
Open CloudServer OCS Chassis 
Specification Version 2.0 
Describes the hardware used in the Version 2.0 (V2.0) OCS 
system, including the chassis, tray, and systems management. 
Open CloudServer OCS Blade 
Specification Version 2.1 
Describes the blade used in the V2.1 OCS system, including 
interconnect and blade hardware and blade management. 
Open CloudServer OCS Tray 
Mezzanine Specification Version 2.0  
Describes the tray mezzanine card used in the V2.0 OCS 
system, including interconnect, hardware, and management. 
Open CloudServer OCS NIC 
Mezzanine Specification Version 2.0  
Describes the Network Interface Controller (NIC) mezzanine 
card used in the V2.0 OCS system. 
Open CloudServer OCS Chassis 
Management Specification Version 
2.0 
Describes the chassis manager command-line interface (CLI). 
This document is intended for designers and engineers who will be building blades for an OCS 
system. 
2 Introduction to the Open CloudServer System 
The V2.0 OCS system is a fully integrated rack of servers and IT equipment that is highly optimized 
and streamlined for large, web-scale deployments.  
OCS is an off-the-shelf (OTS) commodity rack that is loaded with up to four modular chassis, each 
with trays, power supplies, power distribution, rack management, system fans, and two side-walls, 
as shown in Figure 1 and Figure 2. 



 
2 January 7, 2016 
 
 
Figure 1: View of OCS with rack  
 
Figure 2: Second view of OCS 
Each chassis supports 12 rack unit (EIA 310-E standard U or 1U, each 17.7" wide and 1.75" tall) trays 
that house up to 24 individual OCS blades (two blades per tray). Blades can be designed to use the 
full width of the tray. It is also possible to use multiple rack units to house a single tall blade, with 
certain restrictions. 
Power, management, and networking are delivered through the tray backplane (TB) and the power 
distribution backplane (PDB). The tray backplane is located at the back of each tray. The power 
distribution backplane attaches vertically to the individual trays on one side and to the power 


Open Compute Project  Open CloudServer OCS Blade 
http://opencompute.org 3 
 
supply unit (PSU) on the other side. This arrangement reduces the current carrying requirements of 
the distribution board, eliminates cabling, and reduces costs.  
Power and management signals are received from the PDB and distributed to the blades by 
Ethernet networking cables that pass through a blind-mate connector and are routed to 
attachments at the rear of the chassis. Note that running the cables through the rear of the blade 
eliminates the need to connect directly to the servers. Once provisioned, the network cabling 
should only be touched when a cable or switch fails or the typology is changed. The type and 
number of networking switches depends on the specific deployment. 
Following are the significant changes from the previous generation (V2.0) of the blade: 
 Support for full width blades 
 Support for the future Intel® Xeon® Processor product family, 135W maximum 
 Support for 8 M.2 Solid-State Drive (SSD) modules 
 Support for a tray mezzanine on the tray backplane 
 Decreased HDD support to enable cooling for 135W processors 
 Eliminated support for 10G networking 
Figure 3 shows an example of a V2.1 OCS blade. 
 
Figure 3: V2.1 OCS half-width blade 
Figure 4 shows an example of a full-width blade V2.1 OCS blade. 


 
4 January 7, 2016 
 
 
Figure 4 V2.1 OCS full-width blade 
3 Blade Block Diagram 
Figure 4 shows the baseline configuration for the blade. Note that this diagram is provided for 
illustration and is not to scale.  Note also that all requirements are specified in the text of this 
document. 


Open Compute Project  Open CloudServer OCS Blade 
http://opencompute.org 5 
 
 
Figure 5: Baseline configuration of blade 
Key features of the blade include: 
 Support for up to four HDDs: two via motherboard connector, two via Serial AT Attachment 
(SATA) cables to the Platform Control Hub (PCH) 
 Support for up to four SATA Small Form Factor (SFF) SSDs via SATA cable to the PCH 
 Support for up to four Samtec Peripheral Component Interconnect Express (PCIe) x8 slots, with 
each slot capable of supporting two M.2 modules through an interposer board  
 Support for a standard PCIe x8 card via a riser attached to the Samtec PCIe x8 edge connector 
 Support for a Network Interface Controller (NIC) mezzanine card 
 Support for a tray backplane mezzanine card 
4 Blade Features 
Table 2 lists features supported by the new blade design. 


 
6 January 7, 2016 
 
Table 2: Blade features 
Processor 
Platform Future Intel® Xeon® Processor  product family platform 
CPU Future Intel® Xeon® Processor product family 
Sockets Dual and single socket operation 
TDP Wattage Up to 135W 
Memory 
DIMM Slots 16 total DIMM slots 
8 DIMMs per CPU 
2 DIMMs per channel 
DIMM Type Double data rate fourth generation (DDR4)  Registered DIMM (RDIMM) with 
Error-Correcting Code (ECC) 
DIMM Speed DDR4-1866, DDR4-2133 
DIMM Size 16GB, 32GB 
Capacities Supported 128GB, 192GB, 256GB, 512GB  
On-board devices 
PCH Intel® C610 series chipset 
SATA 10 ports @ 6.0 Gb/s 
Server management 
Chipset Baseboard Management Controller (BMC)-lite BMC Aspeed AST1050, serial 
through the Chassis Manager 
Interface Representational State Transfer (REST) API 
Windows Management Interface (WMI) 
Open Management Interface (OMI) 
Command-Line Interface (CLI) 
System firmware 
Version, Vendor Unified Extensible Firmware Interface (UEFI) 2.3.1 
Security Trusted Platform Module (TPM 2.0) 
Secure Boot 
PCI-Express expansion 
4 Samtec PCIe x8 slot Slots 1-3 supports M.2 interposer modules 
Slot 4 supports 1 PCI-Express (PCIe) x8 riser or M.2 interposer module 
Tray Mezzanine Card Supports PCIe x16 mezzanine with bifurcation down to PCIe 4x4 



Open Compute Project  Open CloudServer OCS Blade 
http://opencompute.org 7 
 
NIC Mezzanine Card Supports PCIe x8 mezzanine 
Networking 
NIC mezzanine card Single 40GbE  
Tray mezzanine card Expansion slot funded by PCIe Gen3 x16 
5 Labelling and Loading Guidelines 
5.1 Component Labelling 
Figure 6 shows the approximate locations of major components on the blade motherboard, along 
with labelling information for referencing the CPU, DIMMs, PCIe riser slots, Hard-Disk Drives 
(HDDs), and SSDs. The sections that follow provide more detail about labelling and loading 
guidelines.   
DIMM C1
DIMM C2
DIMM D1
DIMM D2
CPU0
DIMM B2
DIMM B1
DIMM A2
DIMM A1
DIMM E1
DIMM E2
DIMM F1
DIMM F2
CPU1
DIMM H2
DIMM H1
DIMM G2
DIMM G1
PCIe Riser Slot #1
PCIe Riser Slot #2
PCH
AST1050
PCIe Riser Slot #3
PCIe Riser Slot #4
AirMax2
PCIe
NIC Mezz
AirMax2
GbE
AirMax2
SAS
Alignment
Alignment
12V
s
S
A
T
A
0
s
S
A
T
A
1
HDD 0
sSATA0
SKU 3.2.3
HDD 1
sSATA1
SKU 3.2.3
sSATA2
 sSATA3
SATA0
SATA1
SATA
2-5
HDD 5
SATA1
HDD 4
SATA0
HDD 3
sSATA3
HDD 2
sSATA2
HDD 9
SATA5
HDD 8
SATA4
HDD 7
SATA3
HDD 6
SATA2
HDD 1
sSATA1
SKU 3.2.1
HDD 0
sSATA0
SKU 3.2.1
 
Figure 6 Major Component Labeling 
5.2 DIMMS 
Figure 6 shows how the DIMMs will be labelled. The DIMMs will be color coded to ease loading. 
Two colors will be used: one color for DIMMs A1,B1,C1,D1,E1,F1,G1,H1, and a second color for 



 
8 January 7, 2016 
 
DIMMs A2,B2,C2,D2,E2,F2,G2,H2. Color coding can use either the DIMM connector body or the 
latch. Note that color selection is at the discretion of the manufacturer. 
5.3 PCIe Riser Slots 
The blade contains four PCIe riser slots, as shown in Figure 6. The slots use Samtec connectors to 
provide PCIe connectivity and to meet the height restrictions of the PCIe modules. All slots can 
support M.2 modules. Slot #4 can support either an M.2 module or a standard PCIe card (via PCIe 
riser). The blade can support both low profile and full height PCIe cards. 
5.4 HDDs 
HDDs shall be labelled as shown in Figure 6.  A label detailing the HDD numbers shall be available on the 
frame for reference by service personnel.  The drives shall be assigned SATA ports as shown in Table 3: 
Disk Drive SATA Port Assignments so that drive locations are common across WCS blades and so that the 
location of a failed drive can be readily serviced.  Loading of the drives shall typically be governed by the 
configuration, but in the event of a configuration supporting partial loading, drives should be loaded in 
numerical order.   
Table 3: Disk Drive SATA Port Assignments 
Disk Drive 10 HDD Config 
sSATA0 HDD 0 
sSATA1 HDD 1 
sSATA2 HDD 2 
sSATA3 HDD 3 
SATA0 HDD 4 
SATA1 HDD 5 
SATA2 HDD 6 
SATA3 HDD 7 
SATA4 HDD 8 
SATA5 HDD 9 
6 PCB Stackup 
Figure 7 shows the recommended 10-layer dual stripline PCB stackup.  The stackup uses standard 
FR4 PCB material.   The PCB thickness requirement will be ~93mils. 
 



Open Compute Project  Open CloudServer OCS Blade 
http://opencompute.org 9 
 
 
Figure 7: PCB Stackup 
 
Table 4 lists the recommended PCIe mapping for the design. This mapping is used to determine 
feasibility of stackup support for the PCIe routing. Note that this is informational only; actual 
implementation may vary. 
Table 4: PCIe port mapping 
CPU PCIe bus Destination Layer 
0 PE1A PCIe riser slot #1 1 and 10 
0 PE1B PCIe riser slot #1 1 and 10 
0 PE2A NIC 3 and 8 
0 PE2B NIC 3 and 8 
0 PE2C Not used  
0 PE2D Not used  
0 PE3A Tray backplane mezzanine 1 and 10 
0 PE3B Tray backplane mezzanine 1 and 10 
0 PE3C Tray backplane mezzanine 3 and 8 
0 PE3D Tray backplane mezzanine 3 and 8 
Layer Name Thickness Copper
Weight (oz)
Soldermask 0.5
Signal 1 SIGNAL 1.9 1.5
Prepreg 2.7
Plane 2 GND VDD GND 1.3 1.0
Core 4.0
Signal 3 SIGNAL GND SIGNAL 1.3 1.0
Prepreg 25.0
Signal 4 GND SIGNAL GND 1.3 1.0
Core 4.0
Plane 5 Power GND Power 2.6 2.0
Prepreg 4.0
Plane 6 Power GND Power 2.6 2.0
Core 4.0
Signal 7 GND SIGNAL GND 1.3 1.0
Prepreg 25.0
Signal 8 SIGNAL GND SIGNAL 1.3 1.0
Core 4.0
Plane 9 GND VDD GND 1.3 1.0
Prepreg 2.7
Signal 10 SIGNAL 1.9 1.5
Soldermask 0.5
Total 93.2 +/-9
Layer Type



 
10 January 7, 2016 
 
CPU PCIe bus Destination Layer 
1 PE1A PCIe riser slot #4 3 and 8 
1 PE1B PCIe riser slot #4 3 and 8 
1 PE2A PCIe riser slot #2 1 and 10 
1 PE2B PCIe riser slot #2 1 and 10 
1 PE2C PCIe riser slot #3 1 and 10 
1 PE2D PCIe riser slot #3 1 and 10 
1 PE3A Not used ---- 
1 PE3B Not used ---- 
1 PE3C Not used ---- 
1 PE3D Not used ---- 
7 High-Speed Interface Topologies 
The sections that follow detail the electrical topologies for the high-speed interfaces connecting the 
external boards/assemblies to the blade.  
7.1 PCIe-to-Tray Backplane Mezzanine Topology 
The blade contains a PCIe x16 Gen3 interface to a mezzanine card on the tray backplane. This link 
connects the CPU to a PCIe port on the mezzanine card. The block diagram in Figure 8 shows the 
connector interfaces and net length estimates for the tray backplane (TBP) and tray mezzanine card 
(TMC). The connector interface between the TBP and the TMC is defined in the V2.0 Open 
CloudServer OCS Chassis Specification. It is estimated that the blade motherboard can support <12” 
of trace between the CPU and the AirMax VS2 connector on the blade. (Note that this is an 
estimate derived for architectural planning and is not intended to replace signal integrity analysis.)  
       Tray Backplane
Tray Mezzanine Card
Blade Motherboard
Airmax
VS2
Airmax
VS2CPU SEAF SEAM PCIe
Port< 2" < 2"< 12"
 
Figure 8: CPU-to-tray backplane mezzanine PCIe link topology 



Open Compute Project  Open CloudServer OCS Blade 
http://opencompute.org 11 
 
7.2 Blade-to-NIC Mezzanine Topology 
The blade contains a NIC mezzanine card to provide small form-factor pluggable (SFP+) and Quad 
SFP (QSFP+) cable connectivity to the network switch, as shown in Figure 9.  It is expected that this 
topology will require a retimer on the blade motherboard close to the AirMax VS2 connector to 
support the SFP+.   
Blade Motherboard
  
 NIC Mezz
Tray Backplane
Airmax
VS2
Airmax
VS2
        40GbE
     Controller
40GbE Port
SEAM SEAF
Port 2
L0
L1
L2
L3
L2
L3
L1
L0 L0
L1
L2
L3
Port 2
Network
SwitchCable
< 3m<1.6"<3.5"
QSFP+
L3
L2
L1
L0
 
Figure 9: NIC 40GbE Topology 
7.3 PCIe M.2 Topology 
The blade contains a PCIe Gen3 interface to an M.2 SSD module. The block diagram in Figure 10 
shows the connector interface for this topology. It is estimated that the blade can support <13.5” of 
trace between the CPU and the HSEC8 high-speed edge card connector on the blade. (Note that 
this is an estimate derived for architectural planning and is not intended to replace signal integrity 
analysis.) 
Blade Motherboard M.2 Module
Edgefinger
ConnCPU 0/1 PCIe
Interface< 2"<13.5"
M.2 Interposer Board
Samtec
HSEC8
Conn
Edgefinger
Conn <3"
PCIe
Conn
 
Figure 10: PCIe M.2 topology 
7.4 Blade PCIe Riser Topology 
The blade contains a PCIe Gen3 interface to standard PCIe card through a riser bridge board. The 
block diagram in Figure 11 shows the connector interface for this topology.  It is estimated that the 
blade can support <12” of trace between the CPU and the standard PCIe connector on the blade.  
(Note that this is an estimate derived for architectural planning and is not intended to replace 
signal integrity analysis.) 



 
12 January 7, 2016 
 
PCIe Bridge BoardBlade Motherboard
PCIe
Conn
Edgefinger
ConnCPU 1
< 5"<12"
PCIe
Conn
PCIe Card
Edgefinger
Conn
PCIe
Interface< 2"
 
Figure 11: Blade PCIe riser topology 
8 Datasafe Storage Support 
The design will support datasafe storage solutions. A datasafe storage device is a device that 
contains nonvolatile storage backup for volatile memory.    Backup power for these devices can be 
supplied by a device local energy source such as a lithium battery or Pfail circuit (M.2.  Supported 
datasafe devices include:  
 M.2 
Uses device local PFAIL circuit. Save initiated by PERST#. 
8.1 M.2 
The design will support M.2 storage in PCIe SLOTS 1-4. If the M.2 contains a local PFAIL solution, the 
solution will reside within the volume space designated for the M.2 module. 
9 Blade Interconnects 
The tray (or other supporting infrastructure) provides the electrical interface to the blade using the 
connectors listed in Table 5 (or their functional equivalents). Note that the choice of these 
connectors is based on a coplanar PCB for power and network distribution.  
Table 5: Blade-to-tray backplane connector list 
Qty Connector description  
Blade connector 
Manufacturer Part Number 
(MPN) 
TBP mating connector MPN 
1 AirMax VS power header, 1x2 (FCI) 10028918-001LF 
(or equivalent) 
(FCI) 10052620-4555P00LF 
(or equivalent) 
2 
AirMax VS2 R/A header —3 
pair x 6 column, 54 contact, 
2mm spacing, 17mm pitch, 
(FCI) 10123543-101LF 
(or equivalent) 
(FCI) 10122643-101LF 
(or equivalent) 
1 AirMax VS2 R/A header —5 
pair x 10 column, 150 
(FCI) 10123529-101LF 
(or equivalent) 
(FCI) 10122665-101LF 
(or equivalent) 



Open Compute Project  Open CloudServer OCS Blade 
http://opencompute.org 13 
 
Qty Connector description  
Blade connector 
Manufacturer Part Number 
(MPN) 
TBP mating connector MPN 
contact, 2mm spacing, 17mm 
pitch 
2 Guide pin receptacle—
10.8mm right angle, 0° key 
(FCI) 10037912-101LF 
(or equivalent) 
(FCI) 10044366-101LF 
(or equivalent) 
The chassis will provide electrical power and signaling to the tray. The tray will provide power to 
the blade. The blade interface to the tray backplane will provide power and high speed signaling for 
the tray mezzanine card on the tray backplane. 
The interface to the tray backplane from a motherboard shall consist of four connectors: 
1. An AirMax power connector for sourcing 12V power from PDB to blade motherboard. 
2. An AirMax VS2 5x10 primarily to interface PCIe x16 Gen 3 to the tray backplane. 
3. An AirMax VS2 3x6 to interface 10GbE and management signals to the tray backplane. 
4. An AirMax VS2 3x6 primarily to interface SAS channels to the tray backplane. 
The total amount of force required to mate the blade to the tray backplane will not exceed 18.6 
pounds throughout the expected service life of the connector set. With the leverage provided by 
the latch at the face of the blade, the force required will not exceed 3.15 pounds. The retention 
force of the connectors is a minimum of 5.66 pounds, which equates to 0.94 pounds minimum 
force at the latch. 
9.1 Tray Backplane Interface 
The power connector used is in the FCI AirMax VS connector family.  Figure 12 shows the power 
connector layout. 



 
14 January 7, 2016 
 
 
Figure 12: AirMax power receptacle pinout arrangement 
Table 6 shows the power receptacle pinout 
Table 6: Power connector pinout 
Pin Signal name Capacity (in A) 
Position 1 GND 40A 
Position 2 12V supply 40A 
The maximum power that can be delivered to a blade through this connector is 480W, assuming 
the connector supports 40A with 30⁰C rise. Above this current, the Hot Swap Controller (HSC) 
should disable power to protect the hardware. 
The signal connectors used are from the FCI AirMax VS2. Figure 13 shows an example of an AirMax 
coplanar connector pair. 
 
Figure 13: Example of a coplanar blade signal connector 
There are three AirMax connectors interfacing the blade to the tray backplane: 


Open Compute Project  Open CloudServer OCS Blade 
http://opencompute.org 15 
 
 AirMax VS2 5x10 connector   
This connector is primarily responsible for interfacing PCIe x16 Gen 3 from the blade CPU to the 
tray mezzanine card on the tray backplane.   
 AirMax VS2 3x6 connector  
This connector is responsible for interfacing 10GbE, 40GbE, and management signals from the 
Blade to the tray backplane. This connector is mate compatible with the V1.0 Open CloudServer 
blade. 
 AirMax VS2 3x6 connector  
This connector is primarily responsible for interfacing eight 12G SAS channels to the tray 
backplane for storage expansion. This connector is mate compatible with the V1.0 Open 
CloudServer blade.  
The previous-generation blade used the AirMax VS 3x6 connector.  Note that the VS and VS2 family 
connectors are plug-in compatible. 
The AirMax connector is organized as a grid, with rows A through L and columns 1 through 10. Note 
that the columns flip from header to receptacle so that the mated pairs match. Figure 14 shows the 
signal connector layout, with the blade header on the left and the tray backplane receptacle on the 
right.  
 
Figure 14: AirMax VS2 pinout arrangement 
9.1.1 AirMax VS2 PCIe Connector 
Table 7 shows the signal breakout for the AirMax PCIe header. 
Table 7: AirMax VS2 PCIe connector pinout 


 
16 January 7, 2016 
 
 
Table 8 describes the signals used in this interface. 
Table 8: AirMax VS2 PCIe signal definitions 
Bus type I/O Logic Definition for three pair, eight column 
PCIE_B2T_TX_DP/N[15:0] O 
Current 
Mode 
Logic 
(CML) 
PCIe Gen 3 data from blade to tray mezzanine 
PCIE_T2B_RX_DP/N[15:0] I CML PCIe Gen3 data from tray mezzanine to blade 
CLK_100M_P/N[3:0] O CML 100MHz PCIe Gen 3 clocks 
PCIE_RESET_N[3:0]  O 3.3V PCIe reset signals 
WAKE_PCIE_N I 3.3V PCIe wake signal 
PCIE_CFG_ID[1:0] I 3.3V 
PCIe configuration ID bits 
Should be connected to General Purpose Input/Output 
(GPIO) on the PCH 
Should be pulled up with minimum 10K ohm resistor 
Has 1K pulldown on tray mezzanine 
00 = 1 x16 bifurcation 
01 = 2 x8 bifurcation 
10 = 4 x4 bifurcation 
11 = N/A 
PCIE_B2T_TX_DP/N[15:0] O CML PCIe Gen 3 data from blade to tray mezzanine 
MEZZ_SDA/SCL I/O 3.3V I2C from blade BMC to tray mezzanine 
MEZZ_PRESENT_N I 3.3V 
Indicates tray mezzanine card is installed 
This signal should be pulled up on the blade and 
grounded on the tray mezzanine card 
MEZZ_EN O 3.3V Enable for tray mezzanine card on-board power 


Open Compute Project  Open CloudServer OCS Blade 
http://opencompute.org 17 
 
Bus type I/O Logic Definition for three pair, eight column 
P12V_MEZZ O 12V Tray mezzanine card 12V power from blade 12V HSC 
(3A) 
BLADE_MATED_N I 3.3V 
Indicates blade is mated to tray backplane through 
AirMax 5x10 
Grounded on tray backplane 
Should be pulled up on blade and used to qualify 12V 
in-rush turn on 
USBP/N I/O CML USB 2.0 from blade 
P5V_USB O 5V 5V USB power (500mA) 
RSVD -- -- Reserved—do not connect 
GND -- -- Ground 
P12V_MEZZ and P5V_USB pins are assumed to support a derated 500mA per pin; therefore, 
P12V_MEZZ supports a derated maximum of 3A, and P5V_USB supports 500mA. 
Table 9 shows how the reset and clock signals are mapped to support each of the bifurcation cases 
for PCIe to the tray mezzanine. 
Table 9: PCIe bifurcation mapping 
 1x16 2x8 4x4 
 SIGNAL NAME 15:0 15:8 7:0 15:12 11:8 7:4 3:0 
PCIE_RESET_N[0] X X  X    
PCIE_RESET_N[1]   X  X   
PCIE_RESET_N[2]      X  
PCIE_RESET_N[3]       X 
CLK_100M_P/N[0] X X  X    
CLK_100M_P/N[1]   X  X   
CLK_100M_P/N[2]      X  
CLK_100M_P/N[3]       X 
9.1.2 AirMax VS2 10/40GbE Connector 
Table 10 shows the pinout for the AirMax 10Gb/40Gb Ethernet header.  



 
18 January 7, 2016 
 
Table 10: AirMax VS2 10/40GbE connector pinout 
 
Table 11 describes the signals used in this interface.  Note that 10G is no longer supported, but still 
defined in the connectors. 
Table 11: AirMax VS2 40GbE signal definitions 
Bus type I/O Logic Definition for three pair, eight column 
ETH40G_TX[3:0]P/N O CML 40Gb Ethernet from blade LOM to QSFP+ connector 
ETH40G_RX[3:0]P/N I CML 40Gb Ethernet from QSFP+ connector to blade NIC mezz 
ENET_40G_SDA/SCL I/O 3.3V I2C from Ethernet controller on blade to QSFP+ 
connector/cable 
ENET40G_PRES_N I 3.3V Indicates presence of 40GbE cable from QSFP+ connector 
SKU_ID<2:0> I 3.3V 3.3V Pu/Pd on TBP indicating the SKU of the tray 
backplane 
P3V3_QSFP O 3.3V QSFP+ and SFP+ cable power 
BLADE_MATED_N I 3.3V 
Indicates blade is mated to tray backplane through 
AirMax 3x6 
Grounded on tray backplane 
Should be pulled up on blade and used to qualify 12V in-
rush turn on 
SERIAL_TX[2:1] I 3.3V 
Serial communication ports from the Chassis Manager 
(CM) to blade 
Two nodes per blade from CM  
SERIAL_RX[2:1] O 3.3V Serial communication port from blade to CM 
Two nodes per blade from CM 
BLADE_EN1 I 3.3V Blade enable signal from CM 
Used to enable the 12V in-rush controller 
GND ETH40G_RX1P GND ETH40G_RX2P GND ETH40G_TX3P A
ETH40G_TX1P ETH40G_RX1N ETH40G_TX2P ETH40G_RX2N ETH40G_RX3P ETH40G_TX3N B
ETH40G_TX1N GND ETH40G_TX2N GND ETH40G_RX3N GND C
GND P3V3_QSFP GND ETH10G_SDA GND ETH10G_RXP D
ETH40G_RX0P P3V3_QSFP ETH40G_SDA ETH10G_SCL RSVD ETH10G_RXN E
ETH40G_RX0N GND ETH40G_SCL SKU_ID0 SKU_ID2 GND F
GND PSU_ALERT_N SERIAL_RX2 SERIAL_RX1 GND ETH10G_TXP G
ETH40G_TX0P ETH40G_PRES_N SERIAL_TX2 SERIAL_TX1 BLADE_EN1 ETH10G_TXN H
ETH40G_TX0N BLADE_MATED_N SKU_ID1 P3V3_QSFP ETH10G_PRES_N GND I
6 5 4 3 2 1



Open Compute Project  Open CloudServer OCS Blade 
http://opencompute.org 19 
 
Bus type I/O Logic Definition for three pair, eight column 
PSU_ALERT_N I 3.3V 
Power supply failure alert 
This signal is active low (open drain) and should be pulled 
up on the motherboard     
RSVD I/O  Reserved—do not connect 
Ground --  Ground pins 
9.1.3 AirMax VS2 SAS Connector 
Table 12 shows the pinout for the AirMax SAS connector. Connector #1 supports SAS lanes 1-8.  
Since external JBODs are no longer supported, this connector may be depopulated. 
Table 12: AirMax VS2 SAS connector pinout 
 
Table 13 describes the signals used in this interface. 
Table 13: AirMax VS2 SAS signal definitions 
Bus type I/O Logic Definition for three pair, eight column 
SAS_TX[8:1] O CML SAS 8-channels from Blade to SAS cable 
SAS_RX[8:1] I CML SAS 8-channels from SAS cable to blade 
RSVD I/O -- Reserved—do not connect 
Ground -- -- Ground pins 
9.1.4 Connector Skew Compensation 
Right-angle AirMax VS2 connector interfaces between the tray backplane and the blade 
motherboard will require signal delay compensation in the PCB to account for differences in pin 
length of a P/N differential pair in the mated connectors. The pin-pair skew can be obtained from 
the connector manufacturer.  
GND SAS_TX6P GND RSVD GND SAS_TX1P A
SAS_RX8P SAS_TX6N RSVD RSVD SAS_RX3P SAS_TX1N B
SAS_RX8N GND RSVD GND SAS_RX3N GND C
GND SAS_RX6P GND SAS_RX4P GND SAS_RX1P D
SAS_TX8P SAS_RX6N SAS_TX5P SAS_RX4N SAS_TX3P SAS_RX1N E
SAS_TX8N GND SAS_TX5N GND SAS_TX3N GND F
GND SAS_TX7P GND SAS_TX4P GND SAS_TX2P G
SAS_RX7P SAS_TX7N SAS_RX5P SAS_TX4N SAS_RX2P SAS_TX2N H
SAS_RX7N GND SAS_RX5N GND SAS_RX2N GND I
6 5 4 3 2 1



 
20 January 7, 2016 
 
Following are the skew compensation divisions between the blade motherboard and the tray 
backplane: 
 AirMax VS2 PCIe connector 
All skew compensation is contained on the blade motherboard. 
 AirMax VS2 GbE connector 
All skew compensation is contained on the Blade Motherboard. 
 AirMax VS2 SAS connector  
Half (50%) of skew compensation is contained on the blade motherboard. Skew compensation 
for the VS2 connector pair is divided equally between the blade motherboard and the tray 
backplane. 
9.2 PCIe M.2 Interposer Modules 
The blade will support the M.2 interposer module, a custom edge card that supports two M.2 SSD 
modules (Next Generation Form Factor [NGFF] cards) in the connectorized SSD socket 3 format per 
the PCIe M.2 specification.   
The interposer edge card interfaces to the blade motherboard through a Samtec HSEC8-150-01-S-
DV-A connector (or equivalent). The interposer module supports the 60mm, 80mm, and 110mm 
form factors (Type 2260, 2280, and 22110). To support two M.2 modules, the connector interface is 
designed to support two PCIe Gen3x4 interfaces as well as the SSD specific signals, per the PCIE M.2 
specification.  
The interface is also designed to support a standard PCIe x8 interface through a separate riser card. 
The bifurcation is communicated through the LINK_WIDTH signal (Pin B3), which should be 
connected to the PCH. The PCIe card will not require I2C or Joint Test Action Group (JTAG) 
connections to the motherboard. Table 14 shows the pinout for supporting only the M.2 interposer 
module. 
Table 14: PCIe M.2 interposer connector pinout 
 Side B connector  Side B connector 
Pin Name Description Pin Name Description 
1 12V 12V power 2 PRSNT1# Hot plug presence detect 
3 12V 12V power 4 12V 12V power 
5 LINK_WIDT
H 
0=1 x8, 1= 2x4 
bifurcation 6 12V 12V power 
7 GND Ground 8 GND Ground 
9 REFCLK2+ 10 CLKREQ1 Ref clock request (OD) 



Open Compute Project  Open CloudServer OCS Blade 
http://opencompute.org 21 
 
 Side B connector  Side B connector 
Pin Name Description Pin Name Description 
11 REFCLK2- Module 2 reference 
clock differential pair 12 CLKREQ2 Ref clock request (OD) 
13 GND Ground 14 SUSCLK Suspend  cock (32.768Khz) 
15 3.3V 3.3V power 16 DAS/DSS# Drive active indicator 
17 DEVSLP Device sleep 18 3.3V 3.3V power 
19 3.3V 3.3V power 20 3.3V 3.3V power 
21 WAKE# Ground 22 PERST# PCIe reset 
23 3.3V STBY 3.3V standby power 24 GND Ground 
25 GND Ground 26 REFCLK1+ Module 1 reference clock 
differential pair 27 PETp(0) Transmitter module 1 
lane 0 differential pair 
28 REFCLK1- 
29 PETn(0) 30 GND Ground 
31 GND Ground 32 PERp(0) Receiver module 1 lane 0 
differential pair 33 PRSNT2# Hotplug detect 34 PERn(0) 
35 GND Ground 36 GND Ground 
37 PETp(1) Transmitter module 1  
lane 1 differential pair 
38 RSVD Reserved 
39 PETn(1) 40 GND Ground 
41 GND Ground 42 PERp(1) Receiver module 1 lane 1 
differential pair 43 GND Ground 44 PERn(1) 
45 PETp(2) Transmitter module 1  
lane 2 differential pair 
46 GND Ground 
47 PETn(2) 48 GND Ground 
49 GND Ground 50 PERp(2) Receiver module 1 lane 2 
differential pair 51 GND Ground 52 PERn(2) 
53 GND Ground 54 GND Ground 
Mechanical key 
55 PETp(3) Transmitter module 1  
lane 3 differential pair 
56 GND Ground 
57 PETn(3) 58 GND Ground 
59 GND Ground 60 PERp(3) Receiver module 1 lane 3 
differential pair 61 RSVD Reserved 62 PERn(3) 
63 PRSNT3# Hot plug detect 64 GND Ground 
65 GND Ground 66 RSVD Reserved 



 
22 January 7, 2016 
 
 Side B connector  Side B connector 
Pin Name Description Pin Name Description 
67 PETp(4) Transmitter module 2  
lane 0 differential pair 
68 RSVD Reserved 
69 PETn(4) 70 GND Ground 
71 GND Ground 72 PERp(4) Receiver module2  lane 0 
differential pair 73 GND Ground 74 PERn(4) 
75 PETp(5) Transmitter module 2  
lane 1 differential pair 
76 GND Ground 
77 PETn(5) 78 GND Ground 
79 GND Ground 80 PERp(5) Receiver module2  lane 1 
differential pair 81 GND Ground 82 PERn(5) 
83 PETp(6) Transmitter module 2  
lane 2 differential pair 
84 GND Ground 
85 PETn(6) 86 GND Ground 
87 GND Ground 88 PERp(6) Receiver module2  lane 2 
differential pair 89 GND Ground 90 PERn(6) 
91 PETp(7) Transmitter module 2  
lane 3 differential pair 
92 GND Ground 
93 PETn(7) 94 GND Ground 
95 GND Ground 96 PERp(7) Receiver module2  lane 3 
differential pair 97 PRSNT4# Hot plug detect 98 PERn(7) 
99 GND Ground 100 GND Ground 
Signals will satisfy the electrical requirements of the PCIe M.2 Specification and the PCIe Card 
Electromechanical Specification. Note that table includes columns to indicate whether a signal is 
required for use by the M.2 interposer module and/or the PCIe riser. Only slot 4 is required to 
support both the M.2 Interposer and PCIe Riser. 
Table 15 provides a brief functional description of each signal.  
Table 15: PCIe M.2 carrier signal definitions 
Bus type I/O Voltage M.2 interposer PCIe riser Definition for three pair, eight 
column 
P12V O 12V  X 12V Input  
P3V3 O 3.3V X X 3.3V Input  
WAKE# I 3.3V X X PCIe Wake for M.2 modules 1 and 
2 



Open Compute Project  Open CloudServer OCS Blade 
http://opencompute.org 23 
 
Bus type I/O Voltage M.2 interposer PCIe riser Definition for three pair, eight 
column 
PERST# O 3.3V X X PCIe Reset for M.2 modules 1 and 
2 
PETP/N(3:0) O  X X PCIe Transmit to M.2 module 1 
PERP/N[3:0] O  X X PCIe Receiver from M.2 module 1 
REFCLK1LP/N O  X X Reference Clock for module 1 
PETP/N[7:4] O  X X PCIe Transmit to M.2 module 2 
PERP/N[7:4] O  X X PCIe Receive from M.2 module 2 
REFCLK2P/N O  X  Reference clock for module 2 
SUSCLK I  X  Suspend Clock for modules 1 and 2 
(32.768Khz) 
CLKREQ1 I  X  Reference Clock Request for 
module 1 
CLKREQ2 I  X  Reference Clock Request for 
module 2 
DEVSLP O  X  
Device Sleep to M.2 modules 1 
and 2 (should be pulled low on 
MB) 
RSVD N/A  X X Reserved (do not connect) 
PRSNT[3:1] I/O  X X 
Present 
Should be connected on MB per 
PCIe specification 
GND I/O  X X Ground 
9.3 NIC Mezzanine Connector 
The blade will support a single NIC mezzanine card. The mezzanine will interface to the blade 
through a Samtec SEAF-20-06.5-L-08-2-A-K-TR connector or equivalent.  
Table 16 lists the compatible connectors. 
Table 16: NIC mezzanine connector part numbers 
Manufacturer Card connector MPN Motherboard connector MPN 
Samtec SEAM-20-03.5-L-08-2-A-K-TR SEAF-20-06.5-L-08-2-A-K-TR 
Molex 45970-2385 45971-2385 



 
24 January 7, 2016 
 
Table 17 shows the pinout for the NIC mezzanine connector.  
Table 17: NIC mezzanine connector pinout 
 
Table 18 describes the signals used in this interface. 
Table 18: NIC mezzanine signal descriptions 
Bus type I/O Logic Definition 
P3E_CPU1_LAN_RX_DP/N[7:0] I CML PCIe Gen3 from the NIC mezzanine to the CPU 
P3E_CPU1_LAN_TX_DP/N[7:0] O CML PCIe Gen3 from the CPU to the NIC mezzanine 
CLK_100M_NIC_PE_DP/N O CML 100MHz PCIe clock 
PCIE_RESET_N O 3.3V PCIe reset 
MEZZ_PRESENT_N I 3.3V Mezzanine present 
Should be GND on mezzanine  
NWK_1_TX[3:0]P/N I CML Port 1 10GbE transmit from mezzanine to tray 
backplane 
NWK_1_RX[3:0]P/N O CML Port 1 10GbE receive from motherboard to tray 
backplane 
NWK_2_TX[3:0]P/N I CML Port 2 40GbE transmit from mezzanine to tray 
backplane 
NWK_2_RX[3:0]P/N O CML Port 2 40GbE receive from tray backplane to 
mezzanine 
SMB_ALERT_N I 3.3V I2C Alert from NIC mezzanine to BMC 
NWK1_PRESENT_N O 3.3V Port 1 cable present indicator from tray backplane 
NWK1_I2C_SDA I/O 3.3V Port1 I2C data to SFP+ cable 
8 CLK_100M_NIC_PE_DP GND SMB_ALERT_N NIC_MEZZ_ID0 PCIE_WAKE_N GND PCIE_RESET_N GND 1
16 CLK_100M_NIC_PE_DN GND NWK2_PRESENT_N SMB_SCL GND P3E_CPU1_LAN_RX_DP<7> GND P3E_CPU1_LAN_TX_DP<0> 9
24 GND MEZZ_PRESENT_N GND SMB_SDA GND P3E_CPU1_LAN_RX_DN<7> GND P3E_CPU1_LAN_TX_DN<0> 17
32 NWK_2_TX0P GND NWK_1_TX1P GND P3E_CPU1_LAN_RX_DP<6> GND P3E_CPU1_LAN_TX_DP<1> GND 25
40 NWK_2_TX0N GND NWK_1_TX1N GND P3E_CPU1_LAN_RX_DN<6> GND P3E_CPU1_LAN_TX_DN<1> GND 33
48 GND NWK_2_TX1P GND NWK_1_TX2P GND P3E_CPU1_LAN_RX_DP<5> GND P3E_CPU1_LAN_TX_DP<2> 41
56 GND NWK_2_TX1N GND NWK_1_TX2N GND P3E_CPU1_LAN_RX_DN<5> GND P3E_CPU1_LAN_TX_DN<2> 49
64 NWK_2_TX2P GND NWK_1_TX3P GND P3E_CPU1_LAN_RX_DP<4> GND P3E_CPU1_LAN_TX_DP<3> GND 57
72 NWK_2_TX2N GND NWK_1_TX3N GND P3E_CPU1_LAN_RX_DN<4> GND P3E_CPU1_LAN_TX_DN<3> GND 65
80 GND NWK_2_TX3P GND NWK_1_RX1N GND P3E_CPU1_LAN_RX_DP<0> GND P3E_CPU1_LAN_TX_DP<4> 73
88 GND NWK_2_TX3N GND NWK_1_RX1P GND P3E_CPU1_LAN_RX_DN<0> GND P3E_CPU1_LAN_TX_DN<4> 81
96 NWK_2_RX0P GND NWK_1_RX2N GND P3E_CPU1_LAN_RX_DP<1> GND P3E_CPU1_LAN_TX_DP<5> GND 89
104 NWK_2_RX0N GND NWK_1_RX2P GND P3E_CPU1_LAN_RX_DN<1> GND P3E_CPU1_LAN_TX_DN<5> GND 97
112 GND NWK_2_RX1N GND NWK_1_RX3N GND P3E_CPU1_LAN_RX_DP<2> GND P3E_CPU1_LAN_TX_DP<6> 105
120 GND NWK_2_RX1P GND NWK_1_RX3P GND P3E_CPU1_LAN_RX_DN<2> GND P3E_CPU1_LAN_TX_DN<6> 113
128 NWK_2_RX2N GND NWK_1_TX0P GND P3E_CPU1_LAN_RX_DP<3> GND P3E_CPU1_LAN_TX_DP<7> GND 121
136 NWK_2_RX2P GND NWK_1_TX0N GND P3E_CPU1_LAN_RX_DN<3> GND P3E_CPU1_LAN_TX_DN<7> NWK2_I2C_SDA 129
144 GND NWK_2_RX3N GND NWK_1_RX0P GND NIC_MEZZ_ID1 GND NWK2_I2C_SCL 137
152 NWK1_I2C_SDA NWK_2_RX3P GND NWK_1_RX0N GND P3V3 P3V3_AUX P12V_AUX 145
160 NWK1_I2C_SCL GND NWK1_PRESENT_N GND P3V3 P3V3 P3V3_AUX P12V_AUX 153



Open Compute Project  Open CloudServer OCS Blade 
http://opencompute.org 25 
 
Bus type I/O Logic Definition 
NWK1_I2C_SCL I 3.3V Port 1 I2C clock to SFP+ cable 
NWK2_PRESENT_N O 3.3V Port 2 cable present Indicator from tray backplane 
NWK2_I2C_SDA I/O 3.3V Port 2 I2C data to QSFP+ cable 
NWK2_I2C_SCL I 3.3V Port 2 I2C clock to QSFP+ cable 
PCIE_WAKE_N I 3.3V PCIe wake  
SMB_SCL O 3.3V I2C to BMC 
SMB_SDA I/O 3.3V I2C to BMC 
NIC_MEZZ_ID[1:0] I 3.3V NIC mezzanine ID 
Should connect to BMC 
P3V3 O 3.3V 3.3V input power 
P3V3_AUX O 3.3V 3.3V auxiliary input power 
P12V_AUX O 12V 12V input power 
Ground -- -- Ground pins 
9.4 SATA Cable Ports 
The board will include support for one x4 Mini-SAS HD connector, supporting the SFF-8643 (or 
equivalent) cable and four x1 SATA connectors for cabling SATA ports from the PCH to the HDDs 
and SSDs. 
9.5 SATA Power Connector 
The board will include four 4-pin Mini-Fit® Jr 5566 series power connectors, P/N: Molex 5566-04A 
(or equivalent). Two connectors are intended to provide power to the Large Form Factor (LFF) HDDs 
and SSDs. Each connector is intended to provide cabled power to two drives. Each connector pin 
has a maximum 13A current capacity.  
The 12V and 5V power rails are supplied directly from the main 12V and 5V power supply rails. 
These rails need to drive at most six 3.5” LFF HDDs or Small Form Factor (SFF) SSDs. Table 19 lists 
the signal names and current capacities. 



 
26 January 7, 2016 
 
Table 19: SATA power connector signal names and current capacities 
Pin Signal name Capacity (in A) 
Pin 1 and 2 GND 26A (Black) 
Pin 3 12V 13A (Yellow) 
Pin 4 5V 13A (Red) 
9.6 SATA HDD Connector 
The board will include two connectors for connecting up to two SATA HDDs to the motherboard.  
The connectors will be FCI P/N 10029364001LF (or equivalent). Table 20 shows the industry 
standard pinout. The remaining two HDDs should be mounted to fixed connectors on the blade 
pan. 
Table 20: SATA HDD connector pinout 
 
Pin Signal Name Signal Description
1 GND Ground
2 A+ Transmit +
3 A- Transmit -
4 GND Ground
5 B- Receive -
6 B+ Receive +
7 GND Ground
Pin Signal Name Signal Description
1 V33 3.3v Power
2 V33 3.3v Power
3 V33 3.3v Power, Pre-charge, 2nd mate
4 Ground 1st Mate
5 Ground 2nd Mate
6 Ground 3rd Mate
7 V5 5v Power, pre-charge, 2nd mate
8 V5 5v Power
9 V5 5v Power
10 Ground 2nd Mate
11 Optional GND -
12 Ground 1st Mate
13 V12 12v Power, Pre-charge, 2nd mate
14 V12 12v Power
15 V12 12v Power
Power
Data



Open Compute Project  Open CloudServer OCS Blade 
http://opencompute.org 27 
 
9.7 LED Cable Connector 
The design will provide connector support for an LED cable for driving the two LEDs on the front 
panel. 
10 Management Subsystem 
Management circuitry for the blade uses the Intel® Manageability Engine (ME) combined with the 
Baseboard Management Controller (BMC). This section describes the requirements for 
management of the blade. Primary features include: 
 Intel® Manageability Engine (ME) 
 BMC chip (ASPEED AST1050) 
 BMC serial link (universal asynchronous receiver/transmitter [UART]) for communication with 
Chassis Manager 
 Low Pin Count (LPC) connection to the chipset to support in-band management 
 Platform Environmental Control Interface (PECI) for CPU out-of-band environmental control 
 FRUID Electrically Erasable Programmable Read-Only Memory (EEPROM) for storage of 
manufacturing data and event  
 Thermal sensors for inlet and exhaust temperature monitoring 
 Power monitoring through the 12V hot swap controller circuitry 
 Service LEDs 



 
28 January 7, 2016 
 
Figure 15 shows the management block diagram.   
Chassis
Manager
                          Blade Motherboard
PCH
BMC
AST1050
16MB BIOS
FLASH
Tray
Backplane
CPU 0
4GB/s
Port 80
POST LEDs
CPU 1
TPM 
Connector CPLD
9.6GT/s
QPI0
QPI1
9.6GT/s
QPI1
QPI0
DMI2
LPC LPC
SPI UART3
UART1
GPIO
UART1
UART2
SKU_ID[2:0]
PECI
PECI
PECI
UART5 BMC Debug
Connector
USB USB 2.0 
Connector
XDP
Connector
GPIO
JUMPER GPIODisable BMC
JUMPER Force Bios Recovery
SATA x1
Connector
SATA x1
Connector
SATA x1
Connector
sSATA[0]
SATA x4
Mini SAS HD
sSATA[1]
SATA[0]
SATA[5:2]
JTAG
JTAG
4-pin Hdr
4-pin Hdr
DMI2
BMC/CM
Connector
Console Dbg
Connector 4-pin Hdr
4-pin Hdr
16MB BMC
FLASH
SPI
GPIO
12V HSCSVID
SVID
VRD
VccIN
VRD
DDR4 C/D
VRD
DDR4 A/B
VRD
VccIN
VRD
DDR4 C/D
VRD
DDR4 A/B
Front Attention LED
GPIO
Rear Attention LED
Power Status LED
BLADE_EN1
BLADE_EN2
BLADE_MATED_N<1:0>
JUMPER Flash Security OverrideGPIO
JUMPER Clear CMOSGPIO
SATA x1
HDD Conn
SATA x1
HDD Conn
SATA x1
Connector
SATA[1]
sSATA[2]
sSATA[3]
DRAM
128MB
CPLD
HDD #4
HDD #3
HDD #4
HDD #1
HDD #2
HDD #3
USB USB 2.0 
Connector
USB
Tray
Mezz
4-pin Hdr
MEZZ_EN
MEZZ_PRESENT_N
GPIO
GPIO
 
Figure 15: Blade management block diagram 
10.1 Baseboard Management Controller 
The design for the BMC is based on the ASPEED AST1050 processor. Primary features of interest for 
the AST1050 include: 
 Embedded ARM926EJ 
 Embedded 16KB/16KB cache 
 Synchronous Dynamic Random Access Memory (SDRAM) memory up to 512MB 
 NOR/NAND/Serial Peripheral Interface (SPI) flash memory 
 I2C System Management Bus (SMBus) controller 
 5 UART 16550 controllers 
 LPC bus interface 
 Up to 152 GPIO pins 
10.2 DRAM 
The BMC requires 128 MB of Double Data Rate 3 (DDR3) memory. 



Open Compute Project  Open CloudServer OCS Blade 
http://opencompute.org 29 
 
10.3 BMC Boot Flash 
The BMC boots from a flash memory device located on the SPI bus. The device size will be 128Mb 
(16MB) minimum. Winbond W25Q128 serial flash memory (or equivalent) is recommended. The 
design will support a socket for this device during pre-production. 
10.4 BIOS Flash 
The blade will support a 128Mb (16MB) flash BIOS located on the PCH SPI bus: Winbond MPN 
W25Q128BVGFIG (or equivalent). It is required to operate at 50 MHz and include Quad I/O Fast 
Read Support. The design will support a socket for this device during pre-production. The design 
shall also include a BIOS recover jumper connected to a PCH GPIO. 
10.5 Serial Links 
The blade is managed from Chassis Manager through a serial port connection to the BMC. There 
are two dedicated 3.3V serial links (UARTs) routed to the blade. The BMC supports a third UART for 
debug use only. The following is a brief description of the BMC UART port assignments and their 
uses: 
 UART3 
Primary communication with CM for control of the blade. 
 UART1 
Secondary communication with CM; primarily used for console debug. 
 UART5 
BMC debug port; connects only to a debug connector on the blade. 
10.6 PECI 
The blade shall use the PECI host controller inside the CPU to support integrated thermal 
monitoring of the two CPU sockets.   
10.7 TPM Module 
The blade will include a connector to support a tamper-proof Trusted Platform Module (TPM) 2.0 
solution. 



 
30 January 7, 2016 
 
10.8 PCH/BMC I2C 
The design will include a number of I2C devices/functions available to the BMC and PCH. The block 
diagram is shown below in Figure 16.  A brief description of the components follows. Some of the 
block components are specific with respect to requirements of the device and its slave address, 
while others (such as voltage regulators) are more general, requiring that the functionality be 
placed on a specific I2C bus but not requiring a specific solution (vendor part number) be used. 
Care should be taken to electrically isolate components that are powered from separate power 
domains, but are located on the same I2C bus. Note that addresses shown are 8-bit address with 
the Read/Write (R/W) bit as the Least Significant Bit (LSB) set to 0 (0xA8=1010100x). Figure 16 
shows a block diagram. 
Intel® 
ME
PCH BMC
AST1050
VRD
CPU0
VRD
DDR4 VDD
VRD
CPU1
VRD
DDR4 VDD
MEXP_SMB0
TMP75
Blade Inlet
0x92
TMP75
Blade Outlet
0x90
MEXP_SMB1
MEXP_SMB2
SD6
AT24C64
FRUID
0xA8
ICS9FGP204 
CLKGEN
0xD0
CPU XDP
Connector
932SQ420 
CLKBUF
0xD2
ICS9ZX21901 
CLKBUF
0xD8
SD4
PCA9617
I2C Extender
VRD
PCH
SMB
SD2
SD3
SML0
SD7SML1
12V
HSC
0x20 or 0x40
Debug
Debug
Debug
Debug
Debug
Tray
Mezzanine
SD5
DebugNIC
Mezzanine
10GbE
Retimer
 
Figure 16: PCH / BMC I2C block diagram 
10.8.1 Voltage Regulators 
Voltage regulators that support I2C or PMBus should be available to PCH MEXP_SMB0, PCH SMB, 
and BMC I2C Port 3. This includes CPU and memory subsystem regulators, at a minimum. The Intel® 



Open Compute Project  Open CloudServer OCS Blade 
http://opencompute.org 31 
 
ME is responsible for enabling power (through a programmable logic device) to any voltage 
regulators that are not on AUX power (i.e., enabled automatically by the presence of 12V). 
10.8.2 Clock Generators and Buffers 
Clock circuitry that supports I2C should be available to PCH MEXP_SMB0, PCH SMBus, and BMC I2C 
Port 3. The block diagram shows three clock devices that are common to this architecture (actual 
implementation may vary). 
10.8.3 FRUID PROM 
The blade will include a 64Kb serial EEPROM MPN AT24C64 (or equivalent) to store manufacturing 
data. The device should be available to PCH MEXP_SMB0, PCH SMB, and BMC I2C Port 3. 
10.8.4 Temperature Sensors 
The blade will include support for a minimum of two temperature sensors, MPN TMP75 (or 
equivalent), for monitoring the inlet and outlet temperatures of the blade. The sensors will be 
available on BMC I2C port 6. Figure 17 shows temperature sensor locations on the blade.   
 
Figure 17: Temperature sensor locations 
10.8.5 Hot Swap Controller 
For in-rush current protection on the blade, an HSC that includes support for the PMBUS 1.2 
interface will be used on the motherboard. The device will support an I2C polling rate of 10ms. The 
HSC will be available to the Intel® ME SML1 and will provide its ALERT# signal to a Multipath 
General-Purpose Input/Output (MGPIO) on the PCH. The Intel ME SML1 will be dedicated to the 
HSC to provide fast response time to power excursions.  


 
32 January 7, 2016 
 
Following is a list of devices known to be supported by the platform requirements (equivalent or 
newer devices may exist): 
 Analog Devices ADM1276 
 Texas Instruments LM25066i  
 Texas Instruments LM25062 
 Texas Instruments LM25063 
Intel® Node Manager requires the ability to read blade power levels from the HSC to detect 
conditions where total blade power exceeds the desired level for power capping. Operation of the 
HSC is controlled by the BLADE_EN1 and BLADE_MATED signals from the tray backplane, as 
described in the sections that follow. 
10.8.5.1 Blade Enable Signal 
The BLADE_EN1 signal is sourced from the Chassis Management Card (CMC) through the tray 
backplane. The signal is active high, and is intended to be connected to the EN input of the HSC. 
The signal driver from the CMC is open-drain. In normal operation, it will be pulled high through a 
resistive termination when a 3.3V regulator on the blade is enabled.  
To disable the power, the CMC pulls the Blade_EN1 signal to reference ground. The Blade_EN1 
signal should not be pulled low on the blade or driven back to the Chassis Manager. 
If BLADE_EN1 is used to disable power to the blade, the BMC will detect this event and disable 
logging to prevent spurious messages from propagating to the log files. 
10.8.5.2 Blade Mated Signal 
The active low Blade[1:2]_Mated_N signals are used to qualify Blade_EN to indicate that the 
connectors have properly mated during blade insertion before the 12V inrush power is turned on.  
These signals should be connected to the UV (undervoltage) input pin of the HSC. The mated signals 
are pulled to ground on the tray backplane through a 100 ohm (Ω) resistor. Both BLADE_MATED_N 
signals from the AirMax VS2 PCIe connector and the AirMax VS2 10/40GbE connector must be 
asserted before 12V inrush power is turned on. 
To support potential blade or tray backplane SKUs in which connectors could be depopulated, the 
BLADE_MATED_N circuitry should allow for depopulation of components to meet the 
BLADE_MATED_N requirement from either connector. 
Figure 18 shows the signal connections and contact sequence. The 3.3V pull-ups shown should be 
derived from the 12V raw input. Note that the block diagram is intended to be functional only and 
does not describe the actual circuitry required for the intended logic. 



Open Compute Project  Open CloudServer OCS Blade 
http://opencompute.org 33 
 
To support possible SKUs of the tray backplane in which connectors can be removed, the design 
should include a method for grounding the BLADE_EN1 pin from the PCIe AirMax connector in case 
this connector is depopulated. This could be accomplished through a BOM load or other methods.   
BLADE Motherboard Tray
Backplane
Tray Mezz
BLADE_EN1
12V
Conditioned
12V Raw
3.3V
BLADE_MATED_N
3.3V GbE Airmax
VS2
Airmax
Power
Short Pin
Short Pin
Long Pin
MINI
FIT
PDB
Edge
Finger
PCIe AirMax
VS2
Hot
Swap
Controller
PCIe AirMax
VS2
Short Pin
Long Pin
BLADE_MATED_N
3.3V
Vin
En
UV
 
Figure 18: HSC functional block diagram 
Following is the connector contact sequence: 
1. Guide pin (GND) engages. 
2. AirMax power connector (12V and GND) and AirMax VS2 long pin (GND) engage. 
o Blade_EN1 and both Blade_Mated_N are high on blade. 
o HSC is disabled. 
3. AirMax VS2 short pins engage.  
o Blade_EN, Blade_Mated_N and all other signal pins engage. 
o Blade_EN1 is high and both Blade_Mated_N are low. 
o HSC is enabled.   
10.8.5.3 Signal Interpretation  
Table 21 describes the HSC controller with regards to the Blade_EN1 and Blade_Mated_N signals.  



 
34 January 7, 2016 
 
Table 21: Signal interpretation 
BLADE_EN1  
on blade 
BLADE_MATED_N  
on blade Blade/hot swap controller status 
1 1 
 No 12V power, no signal connection to backplane 
 Blade was either not inserted or recently removed 
 Hot swap controller is DISABLED 
1  0 
 Blade is installed, 12V is present 
 Signal connector is mated 
 CM is either not present or is driving high 
 Hot swap controller is ENABLED 
0 1 
 Invalid or faulty state  
 The only way to drive BLADE_EN1 low is from the CM through 
the signal connector  
 If either BLADE_MATED_N is high, the connection was not 
made 
 Hot swap controller is DISABLED 
0 0 
 Blade is installed, 12V is present 
 Both Signal connector are mated 
 CM drives BLADE_EN1 low 
 Hot swap controller is DISABLED 
10.8.6 PCIe I2C 
The blade will support I2C for the tray mezzanine card and the NIC mezzanine card. It is expected 
that standard PCIe modules will support Address Resolution Protocol (ARP) per the I2C 
specification. This should be verified with the specification for specific mezzanine cards. The 
modules shall be accessible to the I2C ports as shown in the block diagram. 
10.9 Intel® Node Manager Hardware Requirements 
Blade management will meet the hardware requirements for support of Intel® Node Manager.  The 
requirements include, but are not limited, to the following: 
 The Intel ME shall be enabled (powered) in all states (i.e., must be power from AUX power). 
 The following signals will be driven or received MGPIO signals of the PCH (additional 
SmaRT/CLST logic will be supported on the PCB): 
o 12V HSC ALERT# 
o SMBAlert#, SMBAlert_EN# 
o PROCHOT# and MEMHOT# for each CPU 



Open Compute Project  Open CloudServer OCS Blade 
http://opencompute.org 35 
 
10.10 Blade LEDs 
The following sections describe the light-emitting diodes (LEDs) used as indicators on the blades 
and chassis. 
Each blade has three LEDs: a front power/status LED that is green/amber, and two attention LEDs 
(front and back) that are red. Figure 19 shows the location of the front LEDs. The location of the 
rear LED is shown in Figure 20. The visible diameter and brightness requirements of the LEDs are 
TBD.  
 
Figure 19: Front blade LED locations 
The rear attention LED is located near the AirMax 3x6 SAS connector, as shown in Figure 20. The 
LED is placed so that it is visible externally through the blade and tray backplane connectors.  
 
Figure 20: Rear attention LED location 
10.10.1 Blade Power Status LED 
When a blade is first inserted, the LED will turn amber if 12V is present at the output of the HSC. 
This ensures that the backplane has 12V power, the tray backplane connectors are mated, and the 
Blade_EN1 signal is asserted.  


 
36 January 7, 2016 
 
When the blade’s management software turns on the system power (CPU/Memory/PCIe), the 
power status LED turns green. Note that the power status LED may be driven by an analog resistor 
network tied directly to a power rail, and is not an indication of the health of the blade. Table 22 
describes the operation of the blade power status LED. 
Table 22: Blade power status LED description 
LED status Condition 
Off Blade is not fully inserted, 12V power is absent, or Blade_EN1 is de-asserted. 
Solid Amber ON Blade is inserted, Blade_EN1 is asserted, 12V power output from the Hot Swap 
Controller is present.  
Solid Green ON Indicates that the BMC is booted and system power is enabled 
(CPU/Memory/PCIe). 
10.10.2 Blade Attention LED 
The blade attention LED directs the service technicians to the blade that requires repair. The 
technician can remove the blade from the rack and replace it with an operational blade.  
The attention LED is driven by a single BMC GPIO. Table 23 describes the operation of the blade 
attention LED. 
Table 23: Blade attention LED description 
LED status Condition 
Off No attention indicated. 
Solid RED System needs attention. 
Note that a second red Attention LED is located at the rear of the blade so that it is visible through 
the tray when the fan door is opened. This LED is set at the same time as the front red attention 
LED, and indicates from the rear of the chassis which blade needs attention. 
10.11 Debug Features 
The following minimum debug features will be included on the motherboard during pre-
production: 
 I2C debug headers on the CPU SMBus, PCH SMBus, Intel ME SML I2C, and BMC I2C.   
Header will be a 3-pin compatible with standard I2C protocol analyzers (such as Beagle Protocol 
Analyzer or Aardvark Host Adapter).  
Note that the CPU SMBus can be eventually accessed through CPU XDP connector. 



Open Compute Project  Open CloudServer OCS Blade 
http://opencompute.org 37 
 
 Debug connector on all three BMC UARTS as shown in the block diagram (Figure 15).   
Connector TBD. 
 Port 80 POST LED support on LPC bus as shown in the block diagram (Figure 15). 
 BIOS debug support including: 
o Socketed BIOS Flash (to be removed for production) 
o BIOS recovery jumper connected to PCH GPIO 
o Flash security override driven from BMC GPIO (to PCH) 
 Power button support. 
 CPU XDP.  
Recommend support for ITP60c, or otherwise ensure that it will be mechanically possible to 
solder on the XDP connector post-production for debug. 
 Dual USB 2.0 headers connected to PCH USB2 Port 1 and Port 9.  
Dongles will be readily available to get standard USB connectors (Port 1 on EHCI#1 and Port 9 on 
EHCI#2 [assuming 0-based numbering] of PCH).  
 USB 2.0 debug port connected to PCH USB2 Port 0 for BIOS and OS debug.   
These can be implemented using 4-pin header connectors to save space. 
 BMC disable jumper attached to GPIO on BMC. 
 Intel ME recovery mode jumper. 
 HW jumper to enable BIOS serial debug output. 
Placement of the debug connectors will not obstruct the installation of any optional assemblies 
such as the PCIe RAID Card or SSDs.  It is acceptable that a debug feature is not accessible if an 
optional assembly is installed unless the feature supports debug of that optional assembly. 
10.12 Power Capping 
The Blade Motherboard shall incorporate power capping by enabling throttling of the CPUs.  
Throttling can be initiated by the following: 
- SMB_ALERT* input of the PCH 
o Driven by the PSU_ALERT# signal 
o Driven by the BMC 
- The ME 
- Undervoltage/Overcurrent monitor of the 12V input detected at the HSC 
 below shows a logical block diagram for this functionality.  Note that additional logic is shown to 
enable control of power capping from either the CM or the BMC and to enable or disable the power 
capping feature.  It is recommended that this logic be implemented in a CPLD if available. 
- When enabled, the typical workflow is as follows: 
o Power Supply drives PSU_ALERT# low 
o PSU_ALERT# drives PROCHOT#/MEMHOT# and PCH SMB_ALERT# (GPIO31) 
o BMC interrupt on PSU_ALERT#  issues default power cap over IPMI link (SML0) 



 
38 January 7, 2016 
 
o BMC deasserts ENABLE signal (to disable PSU_ALERT# monitoring) 
o PROCHOT# switch is reset by BMC when default power cap is removed.  This re-arms the 
functionality by unmasking PSU_ALERT# and asserting PSU_ALERT_EN 
- Additionally 
o BMC can manually assert/deassert PCH SMB_ALERT# using FM_NM_THROTTLE# 
o BMC can enable/disable the power capping features using PSU_ALERT_EN 
o PSU_ALERT# can be asserted by SMALERT# from the PSU or directly from the BMC 
o PROCHOT#/MEMHOT# can be asserted by overcurrent/undervoltage monitor of 12V 
 
ChassisBlade Motherboard
PCH BMC
CPU0
CPU1
GPIOF6
Chassis 
Manager
PSU
x6Intel
ME
SMLINK
UART 4
UART 1
GPIOF7
GPIO31
SMB_ALERT#
FOR CE
PSU_ALERT#
ENABLE
GPIOH6
IPMI
SMALRT#
Under
Voltage 
Monitor
HSCOver
Current
 Monitor
12V
PROCHOT #
MEMHO T#
OC#
UV#
PCAP#
PROCHOT # / MEMHO T#
PSU_ALERT
GPIO
 
Figure 21. Power Capping Block Diagram 
10.13 Tray Mezzanine Power Control 
The 12V power to the tray mezzanine is sourced directly from the output of the Hot Swap 
Controller, and is therefore always present when the HSC is enabled. MEZZ_EN is provided as a 
means to disable power to the tray mezzanine without removing power from the blade. 
10.14 Connector Quality 
The V2.0 Open CloudServer is designed for use in datacenters with a wide range of humidity (up to 
90%). The connectors for these deployments must be capable of withstanding high humidity during 
shipping and installation. The baseline for plating DIMMs and PCIe connectors will be 30μ”-thick 
gold. DIMM connectors must also include lubricant/sealant applied by the connector manufacturer 
that can remain intact after soldering and other manufacturing processes. The sealant is required 
to displace any voids in the connector gold plating. 



Open Compute Project  Open CloudServer OCS Blade 
http://opencompute.org 39 
 
10.15 Overcurrent Protection 
The hot swap controller (HSC) and associated circuitry is responsible for monitoring the 12V input 
current to the blade.  There are two levels of overcurrent protection associated with this monitoring.   
 Over-current protection is responsible for detecting a current level that indicates a catastrophic 
failure of the blade.  In this event, the HSC should disable 12V to the blade typically by disabling 
the HSC’s input FETS.  The recommended current threshold for over-current protection is 50A. 
 Over-current monitor is responsible for detecting a current level that which is higher than 
achievable limits by worst case applications.  In this event, the blade typically throttles the CPU 
performance using the PROCHOT# input.  It is expected that the current threshold be set high 
enough or with slow enough filter response to prevent throttling during performance or stress 
testing with worst case configuration.  The recommended current threshold for over-current 
monitoring is 45A. 
11 NIC Mezzanine 
The V2.0 OCS motherboard will support a 40GbE NIC mezzanine card. The network controller on 
the NIC mezzanine will interface to CPU0 through a PCIe x8 channel.  40GbE is supported through 
Port 2 of the NIC to the blade connector interface. The 40G port will connect to a QSFP+ connector 
on the tray backplane. Figure 22 shows the NIC block diagram. The pinout for the NIC mezzanine is 
described in Section 9.3. Mechanical outlines can be found in the Open CloudServer OCS NIC 
Mezzanine Specification Version 2.0. 
Blade Motherboard
  
 NIC Mezz
Tray Backplane
Airmax
VS2
Airmax
VS2
        40GbE
     Controller
40GbE Port
SEAM SEAF
Port 2
Port 1
L0
L1
L2
L3
L0
L1
L2
L3
L2
L3
L1
L0
L0
L1
L2
L3
L0
L1
L2
L3
Port 2
Port 1
PCIe
CPU0
PCIe PCIe
Network
SwitchCable
< 3m<1.6"<3.5"
QSFP+
L3
L2
L1
L0
 
Figure 22:  NIC block diagram 
12 Blade Electrical Specifications 
The following sections provide specifications for the blade input voltage and current, as well as the 
primary blade signals. 



 
40 January 7, 2016 
 
12.1 Input Voltage, Power, and Current 
Table 24 lists the nominal, maximum, and minimum values for the blade input voltage. The 
maximum and minimum voltages include the effects of connector temperature, age, noise/ripple, 
and dynamic loading. 
Table 24: Input voltage range 
Nominal voltage Maximum voltage Minimum voltage 
12.3V DC 14V DC 11V DC 
The maximum amount of power allowed per blade is defined during system power allocation. The 
number of blades in a chassis might be limited by the capacity of the AC power cord or by the 
cooling capacity of the deployment. Table 25 lists the input power allocation for a low-power blade. 
Table 25: Input power and current allocation 
 Nominal voltage System power allocation 
to blade assembly (in W) Allocated current (in A) 
Low-power blade 
(1x power 
connector) 
12.3VDC 300W 30A 
The blade provides inrush current control through the 12V bus rail; return-side inrush control is not 
used. The inrush current rises linearly from 0A to the load current over a 5 millisecond (ms) period. 
12.2 Current Interrupt Protection and Power, Voltage, and Current 
Monitoring 
The blade provides a cost-effective way to measure and report blade voltage and current 
consumption, and to make instance reporting available to the system. The blade will include power 
consumption measurements at the inrush controller.  Accuracy of the measurement will be +/- 2%.  
The blade also provides a way to interrupt current flow within 1 microsecond (μs) of exceeding the 
maximum current load. 
12.3 Filtering and Capacitance 
The blade provides sufficient filtering to operate with a 0.25A/ μs DC source.  



Open Compute Project  Open CloudServer OCS Blade 
http://opencompute.org 41 
 
Maximum capacitance allowed on the 12V input to the blade is 4,000μFarads (μF). Minimum 
capacitance allowed per blade is 300μF. 
12.4 Grounding and Return 
The blade chassis grounding/return is provided to the blade from the tray backplane through the 
tray backplane/blade interface connectors, including the 12V power connector, guide pins, and 
signal connectors. Chassis ground and logic ground are tied together on the tray backplane and 
should not be separated on the blade. 
13 Blade Physical Specifications 
The physical specifications for the blades include the dimensions of the space into which the blade 
is installed, blade weight limits, a description of the guiding and latching features, and information 
about electromagnetic interference shielding. 
13.1 Blade Mechanical Control Outline 
Figure 23 shows the outline for the blade mechanical controls; note that the locations shown for 
the connectors interfacing to the tray backplane are mandatory, but locations for other connectors, 
components, and mounting holes are suggestions and can be modified to meet the requirements of 
the PCB implementation.  
 Mounting holes 
Figure 23 provides guidelines for mounting holes; actual mounting hole locations may vary to 
meet PCB implementation requirements. 
 NIC mezzanine keepout 
Figure 23 does not include component height restrictions for the NIC mezzanine. For 
information concerning the component height restrictions, see Open CloudServer NIC Mezzanine 
Specification Version 2.0. 
 RAID/ROC card 
Figure 23 shows the component height restrictions for supporting PCIe cards, such as the 
RAID/RAID on Chip (ROC).  Note that the RAID card can include a local Supercap or battery 
backup solution; mounting for this should be accounted for by the mechanical design. 



 
42 January 7, 2016 
 
 
Figure 23: Mechanical control outline 
13.2 Volumetric Specifications 
The outer surfaces of the blade must fit into the volume defined in Figure 24, with all tolerances 
and manufacturing methods accounted for; no features of the blade (including the latch and the 
handle) can extend beyond the specified distance from the front column of the rack so that the 
front door of the rack can be closed without interference.  
This specification assumes a coplanar power/network distribution PCB; if another structure is used, 
the connectors need to be form, fit, and functionally compatible with this specification. Note that if 
necessary, an electromagnetic interference (EMI) enclosure can be built to fit within the volumetric 
restrictions.  


Open Compute Project  Open CloudServer OCS Blade 
http://opencompute.org 43 
 
 
 
Figure 24: Dimensions of the volume that holds the blade 
Each rack unit (or level) within the chassis enclosure can accommodate either two half-width blades 
inserted next to each other or a single full-width blade. Figure 25 shows two blades on a tray.  
 
 
Figure 25: Two blades on a single tray 


 
44 January 7, 2016 
 
Figure 26 shows the dimensions of the blade-mounting envelope, which holds the blade on the 
tray.  
 
Figure 26: Blade-mounting envelope, rear view 


Open Compute Project  Open CloudServer OCS Blade 
http://opencompute.org 45 
 
Note that the only serviceable components in the blade are the hard drives, which can be replaced 
without tools. All other repairs to the blade are made in a bench-top environment. Components 
such as heat sinks, hard drives, and mother boards can be attached so that removal requires a tool, 
if this option is less expensive. 
13.3 Weight and Structure 
Because the tray can support a total weight of 50 lbs, a standard blade should not exceed a static 
weight of 25 lbs when loaded with all options.  
The blade must be mechanically stiff enough to support its own weight during shipping and 
handling. The side walls of the blade should be made as tall as possible within the given envelope to 
maximize the stiffness of the blade structure. 
The blade shall contain a dimple on the side of the front surface to force the blades to fit tightly in 
the tray and prevent excessive bowing in the trays during a shock.  Figure 27 shows an example. 
 
Figure 27: Front surface dimple 
13.4 Guiding and Latching Features 
The sections that follow describe guiding and latching features for the blade. 
13.4.1 Latching Feature Identification 
Latches, as well as thumb screws and other components used to lock, unlock, or remove a 
subassembly from the chassis, are colored blue (Pantone code 285 C blue) to make them easy to 
identify. The locking feature used to secure the blade latch to the front of the blade must provide 
locking with minimal hand motion. A screw type lock with more than a half-turn rotation is not 
permitted. 


 
46 January 7, 2016 
 
If the identity and function of a latching feature for a particular field replaceable unit (FRU) is clear, 
coloring might not be required. For example, a lock/unlock indicator is sufficient for a blade lever. 
13.4.2 Guiding and Latching 
Because a single tray design without a center rail is used for both half-width and full-width blades, 
guides and alignment features are located in both the front and back of the enclosure. These 
features are especially important when inserting a half-width blade into an empty tray.  
The blade enclosure interfaces with the side walls of the tray and the guide pin in the tray to make 
sure the blade is aligned within the ±3.50mm (±0.138”) tolerance necessary to engage the 
connector. The guide pin in the tray aligns the half-width blades with the correct side of the tray. 
The blade connectors are protected from damage by the guide pin by the blade sheet metal. 
Figure 28 shows the blade guiding and latching features associated with the tray. Blade guide pins 
slide into slots on the front of the tray for alignment. A latch attached to the blade fits into a notch 
in the tray to secure the blade in place. 



Open Compute Project  Open CloudServer OCS Blade 
http://opencompute.org 47 
 
 
Figure 28: Guide and latch details, top view 
Figure 29 and Figure 30 show examples of a front-blade guide and latch and of a rear-blade guide.  
Note that a lever is included at the front of the blade to provide additional guidance when the 
blade is locking into the tray, and to help with the force required to install and remove the blade 
from the tray. 


 
48 January 7, 2016 
 
  
Figure 29. Example of a front-blade guide and latch 
 
Figure 30: Example of a rear-blade guide pin 
13.4.3 Electromagnetic Interference Mitigation 
For EMI containment, an EMI shield is added to the top rear edge of the tray, as shown in Figure 31. 
EMI containment will be executed at the blade-assembly level, and EMI certification will be 
executed at the chassis level. 


Open Compute Project  Open CloudServer OCS Blade 
http://opencompute.org 49 
 
 
Figure 31: Tray with EMI enclosure, blade volume shown 
When all trays are in place, they are electrically stitched together to prevent leakage of 
electromagnetic fields. The blade also has a gasket on the front of the top surface that provides 
electrical sealing, as shown in Figure 32. Dimensions for this gasket are shown in Figure 24. 
 
Figure 32: Blade EMI seal 
14 Blade Thermal Design 
To achieve high reliability required for use at scale, the blade must be designed to meet or exceed 
the thermal specifications of all components.  Since the fans used to cool the blades are shared 
with other blades within the chassis, the blades are to be designed to operate according to the 
impedance and airflow curves provided in the Cooling System Specifications chapter of the Open 
CloudServer OCS Chassis Specification Version 2.0 document.  Fan operation and communication 
with chassis management software to set the fan speed are fully described in that chapter. 
 
